# S9S_MB_2U (Grand Teton) — schematic netlist excerpt (pin names and nets, part order shuffled) for the footprints in the layout excerpt that follows; sources: Cadence DE-HDL packaged netlist, KiCad conversion of 03242023_DA0F0TMBIJ0_F0T_Motherboard_J_brd_V01_OCP.brd

C1914  Q_CAP  0.01UF 50V 10% X7R  pkg C0402  page 217 : A = P3V3_AUX_FPGA_VCCIO0 ; B = GND
C1932  Q_CAP  0.01UF 50V 10% X7R  pkg C0402  page 217 : A = P3V3_AUX_FPGA_VCCIO0 ; B = GND
PC314_P0_1  Q_CAP  22UF 4V 20% X6S  pkg C0805  page 267 : A = PVCCIN_CPU0 ; B = GND

(kicad_pcb
	(version 20260206)
	(generator "pcbnew")
	(generator_version "10.0")
	(general
		(thickness 1.6)
		(legacy_teardrops no)
	)
	(paper "A4")
	(title_block
		(title "03242023_DA0F0TMBIJ0_F0T_Motherboard_J_brd_V01_OCP.brd")
		(comment 1 "Grand Teton / footprints 4743-4745 of 6105")
	)
	(layers
		(0 "F.Cu" signal "TOP")
		(4 "In1.Cu" signal "GND")
		(6 "In2.Cu" signal "IN1")
		(8 "In3.Cu" signal "GND1")
		(10 "In4.Cu" signal "IN2")
		(12 "In5.Cu" signal "GND2")
		(14 "In6.Cu" signal "IN3")
		(16 "In7.Cu" signal "GND3")
		(18 "In8.Cu" signal "VCC")
		(20 "In9.Cu" signal "VCC1")
		(22 "In10.Cu" signal "GND4")
		(24 "In11.Cu" signal "IN4")
		(26 "In12.Cu" signal "GND5")
		(28 "In13.Cu" signal "IN5")
		(30 "In14.Cu" signal "GND6")
		(32 "In15.Cu" signal "IN6")
		(34 "In16.Cu" signal "GND7")
		(2 "B.Cu" signal "BOTTOM")
		(9 "F.Adhes" user "F.Adhesive")
		(11 "B.Adhes" user "B.Adhesive")
		(13 "F.Paste" user "Package Geometry/Pastemask Top")
		(15 "B.Paste" user "Package Geometry/Pastemask Bottom")
		(5 "F.SilkS" user "Ref Des/Silkscreen Top")
		(7 "B.SilkS" user "Ref Des/Silkscreen Bottom")
		(1 "F.Mask" user "Board Geometry/Soldermask Top")
		(3 "B.Mask" user "Board Geometry/Soldermask Bottom")
		(17 "Dwgs.User" user "User.Drawings")
		(19 "Cmts.User" user "User.Comments")
		(21 "Eco1.User" user "User.Eco1")
		(23 "Eco2.User" user "User.Eco2")
		(25 "Edge.Cuts" user "Board Geometry/Outline")
		(27 "Margin" user)
		(31 "F.CrtYd" user "Package Geometry/Place Bound Top")
		(29 "B.CrtYd" user "Package Geometry/Place Bound Bottom")
		(35 "F.Fab" user "Ref Des/Assembly Top")
		(33 "B.Fab" user "Ref Des/Assembly Bottom")
	)
	(footprint ""
		(layer "B.Cu")
		(at 343.524332 -324.873366 -90)
		(property "Reference" "PC314_P0_1"
			(at 0 0 90)
			(layer "B.SilkS")
			(hide yes)
			(effects
				(font
					(size 1.27 1.27)
				)
				(justify mirror)
			)
		)
		(property "Value" ""
			(at 0 0 90)
			(layer "B.Fab")
			(effects
				(font
					(size 1.27 1.27)
				)
				(justify mirror)
			)
		)
		(duplicate_pad_numbers_are_jumpers no)
		(fp_line
			(start -1.524 0.762)
			(end 1.524 0.762)
			(stroke
				(width 0.1524)
				(type default)
			)
			(layer "B.SilkS")
		)
		(fp_line
			(start 1.524 0.762)
			(end 1.524 -0.762)
			(stroke
				(width 0.1524)
				(type default)
			)
			(layer "B.SilkS")
		)
		(fp_line
			(start -1.524 -0.762)
			(end -1.524 0.762)
			(stroke
				(width 0.1524)
				(type default)
			)
			(layer "B.SilkS")
		)
		(fp_line
			(start 1.524 -0.762)
			(end -1.524 -0.762)
			(stroke
				(width 0.1524)
				(type default)
			)
			(layer "B.SilkS")
		)
		(fp_line
			(start -1.1049 0.724916)
			(end -1.1049 -0.724916)
			(stroke
				(width 0.1)
				(type default)
			)
			(layer "B.Fab")
		)
		(fp_line
			(start 1.1049 0.724916)
			(end -1.1049 0.724916)
			(stroke
				(width 0.1)
				(type default)
			)
			(layer "B.Fab")
		)
		(fp_line
			(start -1.1049 -0.724916)
			(end 1.1049 -0.724916)
			(stroke
				(width 0.1)
				(type default)
			)
			(layer "B.Fab")
		)
		(fp_line
			(start 1.1049 -0.724916)
			(end 1.1049 0.724916)
			(stroke
				(width 0.1)
				(type default)
			)
			(layer "B.Fab")
		)
		(pad "1" smd rect
			(at 0.889 0 270)
			(size 1.016 1.27)
			(layers "B.Cu" "B.Mask" "B.Paste")
			(net "PVCCIN_CPU0")
		)
		(pad "2" smd rect
			(at -0.889 0 270)
			(size 1.016 1.27)
			(layers "B.Cu" "B.Mask" "B.Paste")
			(net "GND")
		)
	)
	(footprint ""
		(layer "B.Cu")
		(at 175.355758 -112.175544 180)
		(property "Reference" "C1914"
			(at 0 0 0)
			(layer "B.SilkS")
			(hide yes)
			(effects
				(font
					(size 1.27 1.27)
				)
				(justify mirror)
			)
		)
		(property "Value" ""
			(at 0 0 0)
			(layer "B.Fab")
			(effects
				(font
					(size 1.27 1.27)
				)
				(justify mirror)
			)
		)
		(duplicate_pad_numbers_are_jumpers no)
		(fp_line
			(start 0.69215 0.2921)
			(end 0.69215 -0.2921)
			(stroke
				(width 0.1524)
				(type default)
			)
			(layer "B.SilkS")
		)
		(fp_line
			(start 0.69215 -0.2921)
			(end -0.69215 -0.2921)
			(stroke
				(width 0.1524)
				(type default)
			)
			(layer "B.SilkS")
		)
		(fp_line
			(start -0.69215 0.2921)
			(end 0.69215 0.2921)
			(stroke
				(width 0.1524)
				(type default)
			)
			(layer "B.SilkS")
		)
		(fp_line
			(start -0.69215 -0.2921)
			(end -0.69215 0.2921)
			(stroke
				(width 0.1524)
				(type default)
			)
			(layer "B.SilkS")
		)
		(fp_line
			(start 0.51435 0.2794)
			(end 0.51435 -0.2794)
			(stroke
				(width 0.1)
				(type default)
			)
			(layer "B.Fab")
		)
		(fp_line
			(start 0.51435 -0.2794)
			(end -0.51435 -0.2794)
			(stroke
				(width 0.1)
				(type default)
			)
			(layer "B.Fab")
		)
		(fp_line
			(start -0.51435 0.2794)
			(end 0.51435 0.2794)
			(stroke
				(width 0.1)
				(type default)
			)
			(layer "B.Fab")
		)
		(fp_line
			(start -0.51435 -0.2794)
			(end -0.51435 0.2794)
			(stroke
				(width 0.1)
				(type default)
			)
			(layer "B.Fab")
		)
		(pad "1" smd circle
			(at 0.40005 0)
			(size 0 0)
			(layers "B.Cu" "B.Mask" "B.Paste")
			(net "P3V3_AUX_FPGA_VCCIO0")
		)
		(pad "2" smd circle
			(at -0.40005 0)
			(size 0 0)
			(layers "B.Cu" "B.Mask" "B.Paste")
			(net "GND")
		)
		(zone
			(layer "B.Cu")
			(hatch none 0.5)
			(connect_pads
				(clearance 0)
			)
			(min_thickness 0.25)
			(keepout
				(tracks not_allowed)
				(vias allowed)
				(pads allowed)
				(copperpour not_allowed)
				(footprints allowed)
			)
			(placement
				(enabled no)
				(sheetname "")
			)
			(fill
				(thermal_gap 0.5)
				(thermal_bridge_width 0.5)
				(island_removal_mode 0)
			)
			(polygon
				(pts
					(xy 175.165258 -112.263174) (xy 175.256698 -112.32134) (xy 175.456088 -112.32134) (xy 175.546258 -112.263174)
					(xy 175.546258 -112.087914) (xy 175.456088 -112.029494) (xy 175.256698 -112.029494) (xy 175.165258 -112.08766)
				)
			)
		)
	)
	(footprint ""
		(layer "B.Cu")
		(at 175.355758 -114.575336 180)
		(property "Reference" "C1932"
			(at 0 0 0)
			(layer "B.SilkS")
			(hide yes)
			(effects
				(font
					(size 1.27 1.27)
				)
				(justify mirror)
			)
		)
		(property "Value" ""
			(at 0 0 0)
			(layer "B.Fab")
			(effects
				(font
					(size 1.27 1.27)
				)
				(justify mirror)
			)
		)
		(duplicate_pad_numbers_are_jumpers no)
		(fp_line
			(start 0.69215 0.2921)
			(end 0.69215 -0.2921)
			(stroke
				(width 0.1524)
				(type default)
			)
			(layer "B.SilkS")
		)
		(fp_line
			(start 0.69215 -0.2921)
			(end -0.69215 -0.2921)
			(stroke
				(width 0.1524)
				(type default)
			)
			(layer "B.SilkS")
		)
		(fp_line
			(start -0.69215 0.2921)
			(end 0.69215 0.2921)
			(stroke
				(width 0.1524)
				(type default)
			)
			(layer "B.SilkS")
		)
		(fp_line
			(start -0.69215 -0.2921)
			(end -0.69215 0.2921)
			(stroke
				(width 0.1524)
				(type default)
			)
			(layer "B.SilkS")
		)
		(fp_line
			(start 0.51435 0.2794)
			(end 0.51435 -0.2794)
			(stroke
				(width 0.1)
				(type default)
			)
			(layer "B.Fab")
		)
		(fp_line
			(start 0.51435 -0.2794)
			(end -0.51435 -0.2794)
			(stroke
				(width 0.1)
				(type default)
			)
			(layer "B.Fab")
		)
		(fp_line
			(start -0.51435 0.2794)
			(end 0.51435 0.2794)
			(stroke
				(width 0.1)
				(type default)
			)
			(layer "B.Fab")
		)
		(fp_line
			(start -0.51435 -0.2794)
			(end -0.51435 0.2794)
			(stroke
				(width 0.1)
				(type default)
			)
			(layer "B.Fab")
		)
		(pad "1" smd circle
			(at 0.40005 0)
			(size 0 0)
			(layers "B.Cu" "B.Mask" "B.Paste")
			(net "P3V3_AUX_FPGA_VCCIO0")
		)
		(pad "2" smd circle
			(at -0.40005 0)
			(size 0 0)
			(layers "B.Cu" "B.Mask" "B.Paste")
			(net "GND")
		)
		(zone
			(layer "B.Cu")
			(hatch none 0.5)
			(connect_pads
				(clearance 0)
			)
			(min_thickness 0.25)
			(keepout
				(tracks not_allowed)
				(vias allowed)
				(pads allowed)
				(copperpour not_allowed)
				(footprints allowed)
			)
			(placement
				(enabled no)
				(sheetname "")
			)
			(fill
				(thermal_gap 0.5)
				(thermal_bridge_width 0.5)
				(island_removal_mode 0)
			)
			(polygon
				(pts
					(xy 175.165258 -114.662966) (xy 175.256698 -114.721132) (xy 175.456088 -114.721132) (xy 175.546258 -114.662966)
					(xy 175.546258 -114.487706) (xy 175.456088 -114.429286) (xy 175.256698 -114.429286) (xy 175.165258 -114.487452)
				)
			)
		)
	)
)
